# S9S_MB_2U (Grand Teton) — schematic netlist excerpt (pin names and nets, part order shuffled) for the footprints in the layout excerpt that follows; sources: Cadence DE-HDL packaged netlist, KiCad conversion of 03242023_DA0F0TMBIJ0_F0T_Motherboard_J_brd_V01_OCP.brd

J27  SCONN288_ADR50017P130CC  SCONN288_ADR50017-P130CC IO  pkg DDR288S_1-1VXB  page 108
  VIN_BULK0  = P12V_S3_AUX_CPU1_NVDIMM
  RFU0  = TP_CHF_CPU1_DIMM1_FRU_0
  VIN_MGMT  = P3V3_AUX
  HSCL  = I3C_SPD_DDREFGH_CPU1_LVC1_SCL_2
  HSDA  = I3C_SPD_DDREFGH_CPU1_LVC1_SDA
  VSS0  = GND
  DQ0_A  = M_F_CPU1_SA_DQ<0>
  VSS1  = GND
  DQ1_A  = M_F_CPU1_SA_DQ<1>
  VSS2  = GND
  DQS0_A_T  = M_F_CPU1_SA_DQS_DP<0>
  DQS0_A_C  = M_F_CPU1_SA_DQS_DN<0>
  VSS3  = GND
  DQ4_A  = M_F_CPU1_SA_DQ<4>
  VSS4  = GND
  DQ5_A  = M_F_CPU1_SA_DQ<5>
  VSS5  = GND
  DQ8_A  = M_F_CPU1_SA_DQ<8>
  VSS6  = GND
  DQ9_A  = M_F_CPU1_SA_DQ<9>
  VSS7  = GND
  DQS1_A_T  = M_F_CPU1_SA_DQS_DP<1>
  DQS1_A_C  = M_F_CPU1_SA_DQS_DN<1>
  VSS8  = GND
  DQ12_A  = M_F_CPU1_SA_DQ<12>
  VSS9  = GND
  DQ13_A  = M_F_CPU1_SA_DQ<13>
  VSS10  = GND
  DQ16_A  = M_F_CPU1_SA_DQ<16>
  VSS11  = GND
  DQ17_A  = M_F_CPU1_SA_DQ<17>
  VSS12  = GND
  DQS2_A_T  = M_F_CPU1_SA_DQS_DP<2>
  DQS2_A_C  = M_F_CPU1_SA_DQS_DN<2>
  VSS13  = GND
  DQ20_A  = M_F_CPU1_SA_DQ<20>
  VSS14  = GND
  DQ21_A  = M_F_CPU1_SA_DQ<21>
  VSS15  = GND
  DQ24_A  = M_F_CPU1_SA_DQ<24>
  VSS16  = GND
  DQ25_A  = M_F_CPU1_SA_DQ<25>
  VSS17  = GND
  DQS3_A_T  = M_F_CPU1_SA_DQS_DP<3>
  DQS3_A_C  = M_F_CPU1_SA_DQS_DN<3>
  VSS18  = GND
  DQ28_A  = M_F_CPU1_SA_DQ<28>
  VSS19  = GND
  DQ29_A  = M_F_CPU1_SA_DQ<29>
  VSS20  = GND
  CB0_A  = M_F_CPU1_SA_CB<0>
  VSS21  = GND
  CB1_A  = M_F_CPU1_SA_CB<1>
  VSS22  = GND
  DQS4_A_T  = M_F_CPU1_SA_DQS_DP<4>
  DQS4_A_C  = M_F_CPU1_SA_DQS_DN<4>
  VSS23  = GND
  CB4_A  = M_F_CPU1_SA_CB<4>
  VSS24  = GND
  CB5_A  = M_F_CPU1_SA_CB<5>
  VSS25  = GND
  ALERT_N  = M_F_CPU1_ALERT_N
  VSS26  = GND
  CS0_A_N  = M_F_CPU1_SA_CS_N<0>
  VSS27  = GND
  CA0_A  = M_F_CPU1_SA_CA<0>
  VSS28  = GND
  CA2_A  = M_F_CPU1_SA_CA<2>
  VSS29  = GND
  CA4_A  = M_F_CPU1_SA_CA<4>
  VSS30  = GND
  CA6_A  = M_F_CPU1_SA_CA<6>
  VSS31  = GND
  PAR_A  = M_F_CPU1_SA_PAR
  VSS32  = GND
  CA0_B  = M_F_CPU1_SB_CA<0>
  VSS33  = GND
  CA2_B  = M_F_CPU1_SB_CA<2>
  VSS34  = GND
  CA4_B  = M_F_CPU1_SB_CA<4>
  VSS35  = GND
  CA6_B  = M_F_CPU1_SB_CA<6>
  VSS36  = GND
  CS0_B_N  = M_F_CPU1_SB_CS_N<0>
  VSS37  = GND
  \lbd||rsp_a_n\  = M_F_CPU1_SA_RSP<0>
  \lbs||rsp_b_n\  = M_F_CPU1_SB_RSP<0>
  VSS38  = GND
  CB4_B  = M_F_CPU1_SB_CB<4>
  VSS39  = GND
  CB5_B  = M_F_CPU1_SB_CB<5>
  VSS40  = GND
  \dqs9_b_t||tdqs9_b_t||dbi4_b_n\  = M_F_CPU1_SB_DQS_DP<9>
  \dqs9_b_c||tdqs9_b_c\  = M_F_CPU1_SB_DQS_DN<9>
  VSS41  = GND
  CB0_B  = M_F_CPU1_SB_CB<0>
  VSS42  = GND
  CB1_B  = M_F_CPU1_SB_CB<1>
  VSS43  = GND
  DQ0_B  = M_F_CPU1_SB_DQ<0>
  VSS44  = GND
  DQ1_B  = M_F_CPU1_SB_DQ<1>
  VSS45  = GND
  DQS0_B_T  = M_F_CPU1_SB_DQS_DP<0>
  DQS0_B_C  = M_F_CPU1_SB_DQS_DN<0>
  VSS46  = GND
  DQ4_B  = M_F_CPU1_SB_DQ<4>
  VSS47  = GND
  DQ5_B  = M_F_CPU1_SB_DQ<5>
  VSS48  = GND
  DQ8_B  = M_F_CPU1_SB_DQ<8>
  VSS49  = GND
  DQ9_B  = M_F_CPU1_SB_DQ<9>
  VSS50  = GND
  DQS1_B_T  = M_F_CPU1_SB_DQS_DP<1>
  DQS1_B_C  = M_F_CPU1_SB_DQS_DN<1>
  VSS51  = GND
  DQ12_B  = M_F_CPU1_SB_DQ<12>
  VSS52  = GND
  DQ13_B  = M_F_CPU1_SB_DQ<13>
  VSS53  = GND
  DQ16_B  = M_F_CPU1_SB_DQ<16>
  VSS54  = GND
  DQ17_B  = M_F_CPU1_SB_DQ<17>
  VSS55  = GND
  DQS2_B_T  = M_F_CPU1_SB_DQS_DP<2>
  DQS2_B_C  = M_F_CPU1_SB_DQS_DN<2>
  VSS56  = GND
  DQ20_B  = M_F_CPU1_SB_DQ<20>
  VSS57  = GND
  DQ21_B  = M_F_CPU1_SB_DQ<21>
  VSS58  = GND
  DQ24_B  = M_F_CPU1_SB_DQ<24>
  VSS59  = GND
  DQ25_B  = M_F_CPU1_SB_DQ<25>
  VSS60  = GND
  DQS3_B_T  = M_F_CPU1_SB_DQS_DP<3>
  DQS3_B_C  = M_F_CPU1_SB_DQS_DN<3>
  VSS61  = GND
  DQ28_B  = M_F_CPU1_SB_DQ<28>
  VSS62  = GND
  DQ29_B  = M_F_CPU1_SB_DQ<29>
  VSS63  = GND
  RFU1  = TP_CHF_CPU1_DIMM1_FRU_1
  VIN_BULK1  = P12V_S3_AUX_CPU1_NVDIMM
  VIN_BULK2  = P12V_S3_AUX_CPU1_NVDIMM
  \pwr_good||fail_n\  = PWRGD_CHF_CPU1_DIMM1
  HSA  = PD_CHF_CPU1_DIMM1_SAA
  RFU2  = TP_CHF_CPU1_DIMM1_FRU_2
  RFU3  = TP_CHF_CPU1_DIMM1_FRU_3
  VSS64  = GND
  DQ2_A  = M_F_CPU1_SA_DQ<2>
  VSS65  = GND
  DQ3_A  = M_F_CPU1_SA_DQ<3>
  VSS66  = GND
  \dqs5_a_c||tdqs5_a_c||dqs5_a_t||tdqs5_a_t\  = M_F_CPU1_SA_DQS_DN<5>
  \dqs5_a_t||tdqs5_a_t\  = M_F_CPU1_SA_DQS_DP<5>
  VSS67  = GND
  DQ6_A  = M_F_CPU1_SA_DQ<6>
  VSS68  = GND
  DQ7_A  = M_F_CPU1_SA_DQ<7>
  VSS69  = GND
  DQ10_A  = M_F_CPU1_SA_DQ<10>
  VSS70  = GND
  DQ11_A  = M_F_CPU1_SA_DQ<11>
  VSS71  = GND
  \dqs6_a_c||tdqs6_a_c||dqs6_a_t||tdqs6_a_t\  = M_F_CPU1_SA_DQS_DN<6>
  \dqs6_a_t||tdqs6_a_t\  = M_F_CPU1_SA_DQS_DP<6>
  VSS72  = GND
  DQ14_A  = M_F_CPU1_SA_DQ<14>
  VSS73  = GND
  DQ15_A  = M_F_CPU1_SA_DQ<15>
  VSS74  = GND
  DQ18_A  = M_F_CPU1_SA_DQ<18>
  VSS75  = GND
  DQ19_A  = M_F_CPU1_SA_DQ<19>
  VSS76  = GND
  \dqs7_a_c||tdqs7_a_c\  = M_F_CPU1_SA_DQS_DN<7>
  \dqs7_a_t||tdqs7_a_t\  = M_F_CPU1_SA_DQS_DP<7>
  VSS77  = GND
  DQ22_A  = M_F_CPU1_SA_DQ<22>
  VSS78  = GND
  DQ23_A  = M_F_CPU1_SA_DQ<23>
  VSS79  = GND
  DQ26_A  = M_F_CPU1_SA_DQ<26>
  VSS80  = GND
  DQ27_A  = M_F_CPU1_SA_DQ<27>
  VSS81  = GND
  \dqs8_a_c||tdqs8_a_c\  = M_F_CPU1_SA_DQS_DN<8>
  \dqs8_a_t||tdqs8_a_t\  = M_F_CPU1_SA_DQS_DP<8>
  VSS82  = GND
  DQ30_A  = M_F_CPU1_SA_DQ<30>
  VSS83  = GND
  DQ31_A  = M_F_CPU1_SA_DQ<31>
  VSS84  = GND
  CB2_A  = M_F_CPU1_SA_CB<2>
  VSS85  = GND
  CB3_A  = M_F_CPU1_SA_CB<3>
  VSS86  = GND
  \dqs9_a_c||tdqs9_a_c\  = M_F_CPU1_SA_DQS_DN<9>
  \dqs9_a_t||tdqs9_a_t\  = M_F_CPU1_SA_DQS_DP<9>
  VSS87  = GND
  CB6_A  = M_F_CPU1_SA_CB<6>
  VSS88  = GND
  CB7_A  = M_F_CPU1_SA_CB<7>
  VSS89  = GND
  RESET_N  = RST_M_EF_CPU1_FPGA_N
  VSS90  = GND
  CS1_A_N  = M_F_CPU1_SA_CS_N<1>
  VSS91  = GND
  CA1_A  = M_F_CPU1_SA_CA<1>
  VSS92  = GND
  CA3_A  = M_F_CPU1_SA_CA<3>
  VSS93  = GND
  CA5_A  = M_F_CPU1_SA_CA<5>
  VSS94  = GND
  CK_T  = M_F_CPU1_CLK_DP<0>
  CK_C  = M_F_CPU1_CLK_DN<0>
  VSS95  = GND
  RFU4  = TP_CHF_CPU1_DIMM1_FRU_4
  CA1_B  = M_F_CPU1_SB_CA<1>
  VSS96  = GND
  CA3_B  = M_F_CPU1_SB_CA<3>
  VSS97  = GND
  CA5_B  = M_F_CPU1_SB_CA<5>
  VSS98  = GND
  PAR_B  = M_F_CPU1_SB_PAR
  VSS99  = GND
  CS1_B_N  = M_F_CPU1_SB_CS_N<1>
  VSS100  = GND
  RFU5  = TP_CHF_CPU1_DIMM1_FRU_5
  RFU6  = TP_CHF_CPU1_DIMM1_FRU_6
  VSS101  = GND
  CB6_B  = M_F_CPU1_SB_CB<6>
  VSS102  = GND
  CB7_B  = M_F_CPU1_SB_CB<7>
  VSS103  = GND
  DQS4_B_C  = M_F_CPU1_SB_DQS_DN<4>
  DQS4_B_T  = M_F_CPU1_SB_DQS_DP<4>
  VSS104  = GND
  CB2_B  = M_F_CPU1_SB_CB<2>
  VSS105  = GND
  CB3_B  = M_F_CPU1_SB_CB<3>
  VSS106  = GND
  DQ2_B  = M_F_CPU1_SB_DQ<2>
  VSS107  = GND
  DQ3_B  = M_F_CPU1_SB_DQ<3>
  VSS108  = GND
  \dqs5_b_c||tdqs5_b_c\  = M_F_CPU1_SB_DQS_DN<5>
  \dqs5_b_t||tdqs5_b_t\  = M_F_CPU1_SB_DQS_DP<5>
  VSS109  = GND
  DQ6_B  = M_F_CPU1_SB_DQ<6>
  VSS110  = GND
  DQ7_B  = M_F_CPU1_SB_DQ<7>
  VSS111  = GND
  DQ10_B  = M_F_CPU1_SB_DQ<10>
  VSS112  = GND
  DQ11_B  = M_F_CPU1_SB_DQ<11>
  VSS113  = GND
  \dqs6_b_c||tdqs6_b_c\  = M_F_CPU1_SB_DQS_DN<6>
  \dqs6_b_t||tdqs6_b_t\  = M_F_CPU1_SB_DQS_DP<6>
  VSS114  = GND
  DQ14_B  = M_F_CPU1_SB_DQ<14>
  VSS115  = GND
  DQ15_B  = M_F_CPU1_SB_DQ<15>
  VSS116  = GND
  DQ18_B  = M_F_CPU1_SB_DQ<18>
  VSS117  = GND
  DQ19_B  = M_F_CPU1_SB_DQ<19>
  VSS118  = GND
  \dqs7_b_c||tdqs7_b_c\  = M_F_CPU1_SB_DQS_DN<7>
  \dqs7_b_t||tdqs7_b_t\  = M_F_CPU1_SB_DQS_DP<7>
  VSS119  = GND
  DQ22_B  = M_F_CPU1_SB_DQ<22>
  VSS120  = GND
  DQ23_B  = M_F_CPU1_SB_DQ<23>
  VSS121  = GND
  DQ26_B  = M_F_CPU1_SB_DQ<26>
  VSS122  = GND
  DQ27_B  = M_F_CPU1_SB_DQ<27>
  VSS123  = GND
  \dqs8_b_c||tdqs8_b_c\  = M_F_CPU1_SB_DQS_DN<8>
  \dqs8_b_t||tdqs8_b_t\  = M_F_CPU1_SB_DQS_DP<8>
  VSS124  = GND
  DQ30_B  = M_F_CPU1_SB_DQ<30>
  VSS125  = GND
  DQ31_B  = M_F_CPU1_SB_DQ<31>
  VSS126  = GND
  G1  = GND
  G2  = GND
  G3  = GND

(kicad_pcb
	(version 20260206)
	(generator "pcbnew")
	(generator_version "10.0")
	(general
		(thickness 1.6)
		(legacy_teardrops no)
	)
	(paper "A4")
	(title_block
		(title "03242023_DA0F0TMBIJ0_F0T_Motherboard_J_brd_V01_OCP.brd")
		(comment 1 "Grand Teton / footprint 1301 of 6105 (J27), pads 275-291 of 291")
	)
	(layers
		(0 "F.Cu" signal "TOP")
		(4 "In1.Cu" signal "GND")
		(6 "In2.Cu" signal "IN1")
		(8 "In3.Cu" signal "GND1")
		(10 "In4.Cu" signal "IN2")
		(12 "In5.Cu" signal "GND2")
		(14 "In6.Cu" signal "IN3")
		(16 "In7.Cu" signal "GND3")
		(18 "In8.Cu" signal "VCC")
		(20 "In9.Cu" signal "VCC1")
		(22 "In10.Cu" signal "GND4")
		(24 "In11.Cu" signal "IN4")
		(26 "In12.Cu" signal "GND5")
		(28 "In13.Cu" signal "IN5")
		(30 "In14.Cu" signal "GND6")
		(32 "In15.Cu" signal "IN6")
		(34 "In16.Cu" signal "GND7")
		(2 "B.Cu" signal "BOTTOM")
		(9 "F.Adhes" user "F.Adhesive")
		(11 "B.Adhes" user "B.Adhesive")
		(13 "F.Paste" user "Package Geometry/Pastemask Top")
		(15 "B.Paste" user "Package Geometry/Pastemask Bottom")
		(5 "F.SilkS" user "Ref Des/Silkscreen Top")
		(7 "B.SilkS" user "Ref Des/Silkscreen Bottom")
		(1 "F.Mask" user "Board Geometry/Soldermask Top")
		(3 "B.Mask" user "Board Geometry/Soldermask Bottom")
		(17 "Dwgs.User" user "User.Drawings")
		(19 "Cmts.User" user "User.Comments")
		(21 "Eco1.User" user "User.Eco1")
		(23 "Eco2.User" user "User.Eco2")
		(25 "Edge.Cuts" user "Board Geometry/Outline")
		(27 "Margin" user)
		(31 "F.CrtYd" user "Package Geometry/Place Bound Top")
		(29 "B.CrtYd" user "Package Geometry/Place Bound Bottom")
		(35 "F.Fab" user "Ref Des/Assembly Top")
		(33 "B.Fab" user "Ref Des/Assembly Bottom")
	)
	(footprint ""
		(layer "F.Cu")
		(at 183.49468 -258.091686)
		(property "Reference" "J27"
			(at 2.19456 -81.755488 0)
			(unlocked yes)
			(layer "F.SilkS")
			(effects
				(font
					(size 0.7874 0.5842)
					(thickness 0.1524)
				)
				(justify left)
			)
		)
		(property "Value" ""
			(at 0 0 0)
			(layer "F.Fab")
			(effects
				(font
					(size 1.27 1.27)
				)
			)
		)
		(duplicate_pad_numbers_are_jumpers no)
		(pad "275" smd rect
			(at 2.050034 52.274978 270)
			(size 0.519938 1.4986)
			(layers "F.Cu" "F.Mask" "F.Paste")
			(net "GND")
		)
		(pad "276" smd rect
			(at 2.050034 53.125116 270)
			(size 0.519938 1.4986)
			(layers "F.Cu" "F.Mask" "F.Paste")
			(net "M_F_CPU1_SB_DQ<23>")
		)
		(pad "277" smd rect
			(at 2.050034 53.975 270)
			(size 0.519938 1.4986)
			(layers "F.Cu" "F.Mask" "F.Paste")
			(net "GND")
		)
		(pad "278" smd rect
			(at 2.050034 54.824884 270)
			(size 0.519938 1.4986)
			(layers "F.Cu" "F.Mask" "F.Paste")
			(net "M_F_CPU1_SB_DQ<26>")
		)
		(pad "279" smd rect
			(at 2.050034 55.675022 270)
			(size 0.519938 1.4986)
			(layers "F.Cu" "F.Mask" "F.Paste")
			(net "GND")
		)
		(pad "280" smd rect
			(at 2.050034 56.524906 270)
			(size 0.519938 1.4986)
			(layers "F.Cu" "F.Mask" "F.Paste")
			(net "M_F_CPU1_SB_DQ<27>")
		)
		(pad "281" smd rect
			(at 2.050034 57.375044 270)
			(size 0.519938 1.4986)
			(layers "F.Cu" "F.Mask" "F.Paste")
			(net "GND")
		)
		(pad "282" smd rect
			(at 2.050034 58.224928 270)
			(size 0.519938 1.4986)
			(layers "F.Cu" "F.Mask" "F.Paste")
			(net "M_F_CPU1_SB_DQS_DN<8>")
		)
		(pad "283" smd rect
			(at 2.050034 59.075066 270)
			(size 0.519938 1.4986)
			(layers "F.Cu" "F.Mask" "F.Paste")
			(net "M_F_CPU1_SB_DQS_DP<8>")
		)
		(pad "284" smd rect
			(at 2.050034 59.92495 270)
			(size 0.519938 1.4986)
			(layers "F.Cu" "F.Mask" "F.Paste")
			(net "GND")
		)
		(pad "285" smd rect
			(at 2.050034 60.775088 270)
			(size 0.519938 1.4986)
			(layers "F.Cu" "F.Mask" "F.Paste")
			(net "M_F_CPU1_SB_DQ<30>")
		)
		(pad "286" smd rect
			(at 2.050034 61.624972 270)
			(size 0.519938 1.4986)
			(layers "F.Cu" "F.Mask" "F.Paste")
			(net "GND")
		)
		(pad "287" smd rect
			(at 2.050034 62.47511 270)
			(size 0.519938 1.4986)
			(layers "F.Cu" "F.Mask" "F.Paste")
			(net "M_F_CPU1_SB_DQ<31>")
		)
		(pad "288" smd rect
			(at 2.050034 63.324994 270)
			(size 0.519938 1.4986)
			(layers "F.Cu" "F.Mask" "F.Paste")
			(net "GND")
		)
		(pad "G1" thru_hole oval
			(at 0 -68.97497)
			(size 2.8194 1.5748)
			(drill oval 2.4384 1.1938)
			(layers "*.Cu" "*.Mask")
			(remove_unused_layers no)
			(net "GND")
			(clearance 0.127)
			(thermal_gap 0.127)
		)
		(pad "G2" thru_hole oval
			(at 0 3.875024)
			(size 2.8194 1.5748)
			(drill oval 2.4384 1.1938)
			(layers "*.Cu" "*.Mask")
			(remove_unused_layers no)
			(net "GND")
			(clearance 0.127)
			(thermal_gap 0.127)
		)
		(pad "G3" thru_hole oval
			(at 0 68.97497)
			(size 2.8194 1.5748)
			(drill oval 2.4384 1.1938)
			(layers "*.Cu" "*.Mask")
			(remove_unused_layers no)
			(net "GND")
			(clearance 0.127)
			(thermal_gap 0.127)
		)
	)
)
